# T6G (Grand Teton) — schematic netlist excerpt (pin names and nets, part order shuffled) for the footprints in the layout excerpt that follows; sources: Cadence DE-HDL packaged netlist, KiCad conversion of 04192023_DAF0TMB3IC0_F0TG_MB_C_brd_V02_OCP.brd

C2427  Q_CAP  22UF 4V 20% X6S  pkg C0402  page 74 : A = PVDDCR_SOC_P1 ; B = GND
R3709  Q_RES  1K 1% CHIP  pkg 0402LF  page 252 : A = PCA9548_PCIE0_ADDR0 ; B = GND

(kicad_pcb
	(version 20260206)
	(generator "pcbnew")
	(generator_version "10.0")
	(general
		(thickness 1.6)
		(legacy_teardrops no)
	)
	(paper "A4")
	(title_block
		(title "04192023_DAF0TMB3IC0_F0TG_MB_C_brd_V02_OCP.brd")
		(comment 1 "Grand Teton / footprints 1177-1178 of 8354")
	)
	(layers
		(0 "F.Cu" signal "TOP")
		(4 "In1.Cu" signal "GND")
		(6 "In2.Cu" signal "IN1")
		(8 "In3.Cu" signal "GND1")
		(10 "In4.Cu" signal "IN2")
		(12 "In5.Cu" signal "GND2")
		(14 "In6.Cu" signal "IN3")
		(16 "In7.Cu" signal "GND3")
		(18 "In8.Cu" signal "VCC")
		(20 "In9.Cu" signal "VCC1")
		(22 "In10.Cu" signal "GND4")
		(24 "In11.Cu" signal "IN4")
		(26 "In12.Cu" signal "GND5")
		(28 "In13.Cu" signal "IN5")
		(30 "In14.Cu" signal "GND6")
		(32 "In15.Cu" signal "IN6")
		(34 "In16.Cu" signal "GND7")
		(2 "B.Cu" signal "BOTTOM")
		(9 "F.Adhes" user "F.Adhesive")
		(11 "B.Adhes" user "B.Adhesive")
		(13 "F.Paste" user "Package Geometry/Pastemask Top")
		(15 "B.Paste" user "Package Geometry/Pastemask Bottom")
		(5 "F.SilkS" user "Ref Des/Silkscreen Top")
		(7 "B.SilkS" user "Ref Des/Silkscreen Bottom")
		(1 "F.Mask" user "Board Geometry/Soldermask Top")
		(3 "B.Mask" user "Board Geometry/Soldermask Bottom")
		(17 "Dwgs.User" user "User.Drawings")
		(19 "Cmts.User" user "User.Comments")
		(21 "Eco1.User" user "User.Eco1")
		(23 "Eco2.User" user "User.Eco2")
		(25 "Edge.Cuts" user "Board Geometry/Outline")
		(27 "Margin" user)
		(31 "F.CrtYd" user "Package Geometry/Place Bound Top")
		(29 "B.CrtYd" user "Package Geometry/Place Bound Bottom")
		(35 "F.Fab" user "Ref Des/Assembly Top")
		(33 "B.Fab" user "Ref Des/Assembly Bottom")
	)
	(footprint ""
		(layer "F.Cu")
		(at 110.85703 -257.74523)
		(property "Reference" "C2427"
			(at 0 0 0)
			(layer "F.SilkS")
			(hide yes)
			(effects
				(font
					(size 1.27 1.27)
				)
			)
		)
		(property "Value" ""
			(at 0 0 0)
			(layer "F.Fab")
			(effects
				(font
					(size 1.27 1.27)
				)
			)
		)
		(duplicate_pad_numbers_are_jumpers no)
		(fp_line
			(start -0.7874 -0.4064)
			(end 0.7874 -0.4064)
			(stroke
				(width 0.1524)
				(type default)
			)
			(layer "F.SilkS")
		)
		(fp_line
			(start -0.7874 0.4064)
			(end -0.7874 -0.4064)
			(stroke
				(width 0.1524)
				(type default)
			)
			(layer "F.SilkS")
		)
		(fp_line
			(start 0.7874 -0.4064)
			(end 0.7874 0.4064)
			(stroke
				(width 0.1524)
				(type default)
			)
			(layer "F.SilkS")
		)
		(fp_line
			(start 0.7874 0.4064)
			(end -0.7874 0.4064)
			(stroke
				(width 0.1524)
				(type default)
			)
			(layer "F.SilkS")
		)
		(fp_line
			(start -0.67945 -0.305054)
			(end -0.12065 -0.305054)
			(stroke
				(width 0.1)
				(type default)
			)
			(layer "F.Fab")
		)
		(fp_line
			(start -0.67945 0.3048)
			(end -0.67945 -0.305054)
			(stroke
				(width 0.1)
				(type default)
			)
			(layer "F.Fab")
		)
		(fp_line
			(start -0.12065 -0.305054)
			(end -0.12065 -0.2794)
			(stroke
				(width 0.1)
				(type default)
			)
			(layer "F.Fab")
		)
		(fp_line
			(start -0.12065 -0.2794)
			(end 0.12065 -0.2794)
			(stroke
				(width 0.1)
				(type default)
			)
			(layer "F.Fab")
		)
		(fp_line
			(start -0.12065 0.2794)
			(end -0.12065 0.3048)
			(stroke
				(width 0.1)
				(type default)
			)
			(layer "F.Fab")
		)
		(fp_line
			(start -0.12065 0.3048)
			(end -0.67945 0.3048)
			(stroke
				(width 0.1)
				(type default)
			)
			(layer "F.Fab")
		)
		(fp_line
			(start 0.120396 0.2794)
			(end -0.12065 0.2794)
			(stroke
				(width 0.1)
				(type default)
			)
			(layer "F.Fab")
		)
		(fp_line
			(start 0.120396 0.3048)
			(end 0.120396 0.2794)
			(stroke
				(width 0.1)
				(type default)
			)
			(layer "F.Fab")
		)
		(fp_line
			(start 0.12065 -0.3048)
			(end 0.67945 -0.3048)
			(stroke
				(width 0.1)
				(type default)
			)
			(layer "F.Fab")
		)
		(fp_line
			(start 0.12065 -0.2794)
			(end 0.12065 -0.3048)
			(stroke
				(width 0.1)
				(type default)
			)
			(layer "F.Fab")
		)
		(fp_line
			(start 0.67945 -0.3048)
			(end 0.67945 0.3048)
			(stroke
				(width 0.1)
				(type default)
			)
			(layer "F.Fab")
		)
		(fp_line
			(start 0.67945 0.3048)
			(end 0.120396 0.3048)
			(stroke
				(width 0.1)
				(type default)
			)
			(layer "F.Fab")
		)
		(pad "1" smd circle
			(at -0.40005 0)
			(size 0 0)
			(layers "F.Cu" "F.Mask" "F.Paste")
			(net "PVDDCR_SOC_P1")
		)
		(pad "2" smd circle
			(at 0.40005 0)
			(size 0 0)
			(layers "F.Cu" "F.Mask" "F.Paste")
			(net "GND")
		)
	)
	(footprint ""
		(layer "F.Cu")
		(at 257.242056 -125.38837 180)
		(property "Reference" "R3709"
			(at 0 0 180)
			(layer "F.SilkS")
			(hide yes)
			(effects
				(font
					(size 1.27 1.27)
				)
			)
		)
		(property "Value" ""
			(at 0 0 180)
			(layer "F.Fab")
			(effects
				(font
					(size 1.27 1.27)
				)
			)
		)
		(duplicate_pad_numbers_are_jumpers no)
		(fp_line
			(start 0.7874 0.4064)
			(end -0.7874 0.4064)
			(stroke
				(width 0.1524)
				(type default)
			)
			(layer "F.SilkS")
		)
		(fp_line
			(start 0.7874 -0.4064)
			(end 0.7874 0.4064)
			(stroke
				(width 0.1524)
				(type default)
			)
			(layer "F.SilkS")
		)
		(fp_line
			(start -0.7874 0.4064)
			(end -0.7874 -0.4064)
			(stroke
				(width 0.1524)
				(type default)
			)
			(layer "F.SilkS")
		)
		(fp_line
			(start -0.7874 -0.4064)
			(end 0.7874 -0.4064)
			(stroke
				(width 0.1524)
				(type default)
			)
			(layer "F.SilkS")
		)
		(fp_line
			(start 0.67945 0.3048)
			(end 0.120396 0.3048)
			(stroke
				(width 0.1)
				(type default)
			)
			(layer "F.Fab")
		)
		(fp_line
			(start 0.67945 -0.3048)
			(end 0.67945 0.3048)
			(stroke
				(width 0.1)
				(type default)
			)
			(layer "F.Fab")
		)
		(fp_line
			(start 0.12065 -0.2794)
			(end 0.12065 -0.3048)
			(stroke
				(width 0.1)
				(type default)
			)
			(layer "F.Fab")
		)
		(fp_line
			(start 0.12065 -0.3048)
			(end 0.67945 -0.3048)
			(stroke
				(width 0.1)
				(type default)
			)
			(layer "F.Fab")
		)
		(fp_line
			(start 0.120396 0.3048)
			(end 0.120396 0.2794)
			(stroke
				(width 0.1)
				(type default)
			)
			(layer "F.Fab")
		)
		(fp_line
			(start 0.120396 0.2794)
			(end -0.12065 0.2794)
			(stroke
				(width 0.1)
				(type default)
			)
			(layer "F.Fab")
		)
		(fp_line
			(start -0.12065 0.3048)
			(end -0.67945 0.3048)
			(stroke
				(width 0.1)
				(type default)
			)
			(layer "F.Fab")
		)
		(fp_line
			(start -0.12065 0.2794)
			(end -0.12065 0.3048)
			(stroke
				(width 0.1)
				(type default)
			)
			(layer "F.Fab")
		)
		(fp_line
			(start -0.12065 -0.2794)
			(end 0.12065 -0.2794)
			(stroke
				(width 0.1)
				(type default)
			)
			(layer "F.Fab")
		)
		(fp_line
			(start -0.12065 -0.305054)
			(end -0.12065 -0.2794)
			(stroke
				(width 0.1)
				(type default)
			)
			(layer "F.Fab")
		)
		(fp_line
			(start -0.67945 0.3048)
			(end -0.67945 -0.305054)
			(stroke
				(width 0.1)
				(type default)
			)
			(layer "F.Fab")
		)
		(fp_line
			(start -0.67945 -0.305054)
			(end -0.12065 -0.305054)
			(stroke
				(width 0.1)
				(type default)
			)
			(layer "F.Fab")
		)
		(pad "1" smd circle
			(at -0.40005 0 180)
			(size 0 0)
			(layers "F.Cu" "F.Mask" "F.Paste")
			(net "PCA9548_PCIE0_ADDR0")
		)
		(pad "2" smd circle
			(at 0.40005 0 180)
			(size 0 0)
			(layers "F.Cu" "F.Mask" "F.Paste")
			(net "GND")
		)
	)
)
